(kicad_pcb
	(version 20260206)
	(generator "pcbnew")
	(generator_version "10.0")
	(general
		(thickness 1.6)
		(legacy_teardrops no)
	)
	(paper "A4")
	(title_block
		(title "04192023_DAF0TMB3IC0_F0TG_MB_C_brd_V02_OCP.brd")
		(comment 1 "Grand Teton / footprints 3127-3134 of 8354")
	)
	(layers
		(0 "F.Cu" signal "TOP")
		(4 "In1.Cu" signal "GND")
		(6 "In2.Cu" signal "IN1")
		(8 "In3.Cu" signal "GND1")
		(10 "In4.Cu" signal "IN2")
		(12 "In5.Cu" signal "GND2")
		(14 "In6.Cu" signal "IN3")
		(16 "In7.Cu" signal "GND3")
		(18 "In8.Cu" signal "VCC")
		(20 "In9.Cu" signal "VCC1")
		(22 "In10.Cu" signal "GND4")
		(24 "In11.Cu" signal "IN4")
		(26 "In12.Cu" signal "GND5")
		(28 "In13.Cu" signal "IN5")
		(30 "In14.Cu" signal "GND6")
		(32 "In15.Cu" signal "IN6")
		(34 "In16.Cu" signal "GND7")
		(2 "B.Cu" signal "BOTTOM")
		(9 "F.Adhes" user "F.Adhesive")
		(11 "B.Adhes" user "B.Adhesive")
		(13 "F.Paste" user "Package Geometry/Pastemask Top")
		(15 "B.Paste" user "Package Geometry/Pastemask Bottom")
		(5 "F.SilkS" user "Ref Des/Silkscreen Top")
		(7 "B.SilkS" user "Ref Des/Silkscreen Bottom")
		(1 "F.Mask" user "Board Geometry/Soldermask Top")
		(3 "B.Mask" user "Board Geometry/Soldermask Bottom")
		(17 "Dwgs.User" user "User.Drawings")
		(19 "Cmts.User" user "User.Comments")
		(21 "Eco1.User" user "User.Eco1")
		(23 "Eco2.User" user "User.Eco2")
		(25 "Edge.Cuts" user "Board Geometry/Outline")
		(27 "Margin" user)
		(31 "F.CrtYd" user "Package Geometry/Place Bound Top")
		(29 "B.CrtYd" user "Package Geometry/Place Bound Bottom")
		(35 "F.Fab" user "Ref Des/Assembly Top")
		(33 "B.Fab" user "Ref Des/Assembly Bottom")
	)
	(footprint ""
		(layer "F.Cu")
		(at 364.362238 -411.369764)
		(property "Reference" "R9005"
			(at 0 0 0)
			(layer "F.SilkS")
			(hide yes)
			(effects
				(font
					(size 1.27 1.27)
				)
			)
		)
		(property "Value" ""
			(at 0 0 0)
			(layer "F.Fab")
			(effects
				(font
					(size 1.27 1.27)
				)
			)
		)
		(duplicate_pad_numbers_are_jumpers no)
		(fp_line
			(start -0.7874 -0.4064)
			(end 0.7874 -0.4064)
			(stroke
				(width 0.1524)
				(type default)
			)
			(layer "F.SilkS")
		)
		(fp_line
			(start -0.7874 0.4064)
			(end -0.7874 -0.4064)
			(stroke
				(width 0.1524)
				(type default)
			)
			(layer "F.SilkS")
		)
		(fp_line
			(start 0.7874 -0.4064)
			(end 0.7874 0.4064)
			(stroke
				(width 0.1524)
				(type default)
			)
			(layer "F.SilkS")
		)
		(fp_line
			(start 0.7874 0.4064)
			(end -0.7874 0.4064)
			(stroke
				(width 0.1524)
				(type default)
			)
			(layer "F.SilkS")
		)
		(fp_line
			(start -0.67945 -0.305054)
			(end -0.12065 -0.305054)
			(stroke
				(width 0.1)
				(type default)
			)
			(layer "F.Fab")
		)
		(fp_line
			(start -0.67945 0.3048)
			(end -0.67945 -0.305054)
			(stroke
				(width 0.1)
				(type default)
			)
			(layer "F.Fab")
		)
		(fp_line
			(start -0.12065 -0.305054)
			(end -0.12065 -0.2794)
			(stroke
				(width 0.1)
				(type default)
			)
			(layer "F.Fab")
		)
		(fp_line
			(start -0.12065 -0.2794)
			(end 0.12065 -0.2794)
			(stroke
				(width 0.1)
				(type default)
			)
			(layer "F.Fab")
		)
		(fp_line
			(start -0.12065 0.2794)
			(end -0.12065 0.3048)
			(stroke
				(width 0.1)
				(type default)
			)
			(layer "F.Fab")
		)
		(fp_line
			(start -0.12065 0.3048)
			(end -0.67945 0.3048)
			(stroke
				(width 0.1)
				(type default)
			)
			(layer "F.Fab")
		)
		(fp_line
			(start 0.120396 0.2794)
			(end -0.12065 0.2794)
			(stroke
				(width 0.1)
				(type default)
			)
			(layer "F.Fab")
		)
		(fp_line
			(start 0.120396 0.3048)
			(end 0.120396 0.2794)
			(stroke
				(width 0.1)
				(type default)
			)
			(layer "F.Fab")
		)
		(fp_line
			(start 0.12065 -0.3048)
			(end 0.67945 -0.3048)
			(stroke
				(width 0.1)
				(type default)
			)
			(layer "F.Fab")
		)
		(fp_line
			(start 0.12065 -0.2794)
			(end 0.12065 -0.3048)
			(stroke
				(width 0.1)
				(type default)
			)
			(layer "F.Fab")
		)
		(fp_line
			(start 0.67945 -0.3048)
			(end 0.67945 0.3048)
			(stroke
				(width 0.1)
				(type default)
			)
			(layer "F.Fab")
		)
		(fp_line
			(start 0.67945 0.3048)
			(end 0.120396 0.3048)
			(stroke
				(width 0.1)
				(type default)
			)
			(layer "F.Fab")
		)
		(pad "1" smd circle
			(at -0.40005 0)
			(size 0 0)
			(layers "F.Cu" "F.Mask" "F.Paste")
			(net "P3V3_AUX")
		)
		(pad "2" smd circle
			(at 0.40005 0)
			(size 0 0)
			(layers "F.Cu" "F.Mask" "F.Paste")
			(net "PRSNT_CABLE_SWB_B1_ISO_N")
		)
	)
	(footprint ""
		(layer "F.Cu")
		(at 368.705892 -378.95403 -90)
		(property "Reference" "C894"
			(at 0 0 270)
			(layer "F.SilkS")
			(hide yes)
			(effects
				(font
					(size 1.27 1.27)
				)
			)
		)
		(property "Value" ""
			(at 0 0 270)
			(layer "F.Fab")
			(effects
				(font
					(size 1.27 1.27)
				)
			)
		)
		(duplicate_pad_numbers_are_jumpers no)
		(fp_line
			(start -0.299974 0.150114)
			(end -0.299974 -0.150114)
			(stroke
				(width 0.1)
				(type default)
			)
			(layer "F.Fab")
		)
		(fp_line
			(start 0.299974 0.150114)
			(end -0.299974 0.150114)
			(stroke
				(width 0.1)
				(type default)
			)
			(layer "F.Fab")
		)
		(fp_line
			(start -0.299974 -0.150114)
			(end 0.299974 -0.150114)
			(stroke
				(width 0.1)
				(type default)
			)
			(layer "F.Fab")
		)
		(fp_line
			(start 0.299974 -0.150114)
			(end 0.299974 0.150114)
			(stroke
				(width 0.1)
				(type default)
			)
			(layer "F.Fab")
		)
		(pad "1" smd rect
			(at -0.2667 0 270)
			(size 0.3048 0.381)
			(layers "F.Cu" "F.Mask" "F.Paste")
			(net "P5E_CPU0_P3_TX_C_DN<3>")
		)
		(pad "2" smd rect
			(at 0.2667 0 270)
			(size 0.3048 0.381)
			(layers "F.Cu" "F.Mask" "F.Paste")
			(net "P5E_CPU0_P3_TX_DN<3>")
		)
	)
	(footprint ""
		(layer "F.Cu")
		(at 321.056 -99.187)
		(property "Reference" "R1350"
			(at 0 0 0)
			(layer "F.SilkS")
			(hide yes)
			(effects
				(font
					(size 1.27 1.27)
				)
			)
		)
		(property "Value" ""
			(at 0 0 0)
			(layer "F.Fab")
			(effects
				(font
					(size 1.27 1.27)
				)
			)
		)
		(duplicate_pad_numbers_are_jumpers no)
		(fp_line
			(start -0.7874 -0.4064)
			(end 0.7874 -0.4064)
			(stroke
				(width 0.1524)
				(type default)
			)
			(layer "F.SilkS")
		)
		(fp_line
			(start -0.7874 0.4064)
			(end -0.7874 -0.4064)
			(stroke
				(width 0.1524)
				(type default)
			)
			(layer "F.SilkS")
		)
		(fp_line
			(start 0.7874 -0.4064)
			(end 0.7874 0.4064)
			(stroke
				(width 0.1524)
				(type default)
			)
			(layer "F.SilkS")
		)
		(fp_line
			(start 0.7874 0.4064)
			(end -0.7874 0.4064)
			(stroke
				(width 0.1524)
				(type default)
			)
			(layer "F.SilkS")
		)
		(fp_line
			(start -0.67945 -0.305054)
			(end -0.12065 -0.305054)
			(stroke
				(width 0.1)
				(type default)
			)
			(layer "F.Fab")
		)
		(fp_line
			(start -0.67945 0.3048)
			(end -0.67945 -0.305054)
			(stroke
				(width 0.1)
				(type default)
			)
			(layer "F.Fab")
		)
		(fp_line
			(start -0.12065 -0.305054)
			(end -0.12065 -0.2794)
			(stroke
				(width 0.1)
				(type default)
			)
			(layer "F.Fab")
		)
		(fp_line
			(start -0.12065 -0.2794)
			(end 0.12065 -0.2794)
			(stroke
				(width 0.1)
				(type default)
			)
			(layer "F.Fab")
		)
		(fp_line
			(start -0.12065 0.2794)
			(end -0.12065 0.3048)
			(stroke
				(width 0.1)
				(type default)
			)
			(layer "F.Fab")
		)
		(fp_line
			(start -0.12065 0.3048)
			(end -0.67945 0.3048)
			(stroke
				(width 0.1)
				(type default)
			)
			(layer "F.Fab")
		)
		(fp_line
			(start 0.120396 0.2794)
			(end -0.12065 0.2794)
			(stroke
				(width 0.1)
				(type default)
			)
			(layer "F.Fab")
		)
		(fp_line
			(start 0.120396 0.3048)
			(end 0.120396 0.2794)
			(stroke
				(width 0.1)
				(type default)
			)
			(layer "F.Fab")
		)
		(fp_line
			(start 0.12065 -0.3048)
			(end 0.67945 -0.3048)
			(stroke
				(width 0.1)
				(type default)
			)
			(layer "F.Fab")
		)
		(fp_line
			(start 0.12065 -0.2794)
			(end 0.12065 -0.3048)
			(stroke
				(width 0.1)
				(type default)
			)
			(layer "F.Fab")
		)
		(fp_line
			(start 0.67945 -0.3048)
			(end 0.67945 0.3048)
			(stroke
				(width 0.1)
				(type default)
			)
			(layer "F.Fab")
		)
		(fp_line
			(start 0.67945 0.3048)
			(end 0.120396 0.3048)
			(stroke
				(width 0.1)
				(type default)
			)
			(layer "F.Fab")
		)
		(pad "1" smd circle
			(at -0.40005 0)
			(size 0 0)
			(layers "F.Cu" "F.Mask" "F.Paste")
			(net "INA230_8_A1")
		)
		(pad "2" smd circle
			(at 0.40005 0)
			(size 0 0)
			(layers "F.Cu" "F.Mask" "F.Paste")
			(net "SMB_INA230_8_3V3AUX_SDA_R1")
		)
	)
	(footprint ""
		(layer "F.Cu")
		(at 24.906732 -343.716864 180)
		(property "Reference" "PC176"
			(at 0 0 180)
			(layer "F.SilkS")
			(hide yes)
			(effects
				(font
					(size 1.27 1.27)
				)
			)
		)
		(property "Value" ""
			(at 0 0 180)
			(layer "F.Fab")
			(effects
				(font
					(size 1.27 1.27)
				)
			)
		)
		(duplicate_pad_numbers_are_jumpers no)
		(fp_line
			(start 0.7874 0.4064)
			(end -0.7874 0.4064)
			(stroke
				(width 0.1524)
				(type default)
			)
			(layer "F.SilkS")
		)
		(fp_line
			(start 0.7874 -0.4064)
			(end 0.7874 0.4064)
			(stroke
				(width 0.1524)
				(type default)
			)
			(layer "F.SilkS")
		)
		(fp_line
			(start -0.7874 0.4064)
			(end -0.7874 -0.4064)
			(stroke
				(width 0.1524)
				(type default)
			)
			(layer "F.SilkS")
		)
		(fp_line
			(start -0.7874 -0.4064)
			(end 0.7874 -0.4064)
			(stroke
				(width 0.1524)
				(type default)
			)
			(layer "F.SilkS")
		)
		(fp_line
			(start 0.67945 0.3048)
			(end 0.120396 0.3048)
			(stroke
				(width 0.1)
				(type default)
			)
			(layer "F.Fab")
		)
		(fp_line
			(start 0.67945 -0.3048)
			(end 0.67945 0.3048)
			(stroke
				(width 0.1)
				(type default)
			)
			(layer "F.Fab")
		)
		(fp_line
			(start 0.12065 -0.2794)
			(end 0.12065 -0.3048)
			(stroke
				(width 0.1)
				(type default)
			)
			(layer "F.Fab")
		)
		(fp_line
			(start 0.12065 -0.3048)
			(end 0.67945 -0.3048)
			(stroke
				(width 0.1)
				(type default)
			)
			(layer "F.Fab")
		)
		(fp_line
			(start 0.120396 0.3048)
			(end 0.120396 0.2794)
			(stroke
				(width 0.1)
				(type default)
			)
			(layer "F.Fab")
		)
		(fp_line
			(start 0.120396 0.2794)
			(end -0.12065 0.2794)
			(stroke
				(width 0.1)
				(type default)
			)
			(layer "F.Fab")
		)
		(fp_line
			(start -0.12065 0.3048)
			(end -0.67945 0.3048)
			(stroke
				(width 0.1)
				(type default)
			)
			(layer "F.Fab")
		)
		(fp_line
			(start -0.12065 0.2794)
			(end -0.12065 0.3048)
			(stroke
				(width 0.1)
				(type default)
			)
			(layer "F.Fab")
		)
		(fp_line
			(start -0.12065 -0.2794)
			(end 0.12065 -0.2794)
			(stroke
				(width 0.1)
				(type default)
			)
			(layer "F.Fab")
		)
		(fp_line
			(start -0.12065 -0.305054)
			(end -0.12065 -0.2794)
			(stroke
				(width 0.1)
				(type default)
			)
			(layer "F.Fab")
		)
		(fp_line
			(start -0.67945 0.3048)
			(end -0.67945 -0.305054)
			(stroke
				(width 0.1)
				(type default)
			)
			(layer "F.Fab")
		)
		(fp_line
			(start -0.67945 -0.305054)
			(end -0.12065 -0.305054)
			(stroke
				(width 0.1)
				(type default)
			)
			(layer "F.Fab")
		)
		(pad "1" smd circle
			(at -0.40005 0 180)
			(size 0 0)
			(layers "F.Cu" "F.Mask" "F.Paste")
			(net "SW_PVDDIO_P1_SW4")
		)
		(pad "2" smd circle
			(at 0.40005 0 180)
			(size 0 0)
			(layers "F.Cu" "F.Mask" "F.Paste")
			(net "SW_PVDDIO_P1_SW4_RC")
		)
	)
	(footprint ""
		(layer "F.Cu")
		(at 104.7623 -389.49376)
		(property "Reference" "R1378"
			(at 0 0 0)
			(layer "F.SilkS")
			(hide yes)
			(effects
				(font
					(size 1.27 1.27)
				)
			)
		)
		(property "Value" ""
			(at 0 0 0)
			(layer "F.Fab")
			(effects
				(font
					(size 1.27 1.27)
				)
			)
		)
		(duplicate_pad_numbers_are_jumpers no)
		(fp_line
			(start -0.32512 -0.175006)
			(end 0.32512 -0.175006)
			(stroke
				(width 0.1)
				(type default)
			)
			(layer "F.Fab")
		)
		(fp_line
			(start -0.32512 0.175006)
			(end -0.32512 -0.175006)
			(stroke
				(width 0.1)
				(type default)
			)
			(layer "F.Fab")
		)
		(fp_line
			(start 0.32512 -0.175006)
			(end 0.32512 0.175006)
			(stroke
				(width 0.1)
				(type default)
			)
			(layer "F.Fab")
		)
		(fp_line
			(start 0.32512 0.175006)
			(end -0.32512 0.175006)
			(stroke
				(width 0.1)
				(type default)
			)
			(layer "F.Fab")
		)
		(pad "1" smd rect
			(at -0.2667 0)
			(size 0.3048 0.381)
			(layers "F.Cu" "F.Mask" "F.Paste")
			(net "RXDET_BYP_RT_CPU1_P1")
		)
		(pad "2" smd rect
			(at 0.2667 0 180)
			(size 0.3048 0.381)
			(layers "F.Cu" "F.Mask" "F.Paste")
			(net "GND")
		)
	)
	(footprint ""
		(layer "F.Cu")
		(at 143.352266 -408.517344 -90)
		(property "Reference" "C6711"
			(at 0 0 270)
			(layer "F.SilkS")
			(hide yes)
			(effects
				(font
					(size 1.27 1.27)
				)
			)
		)
		(property "Value" ""
			(at 0 0 270)
			(layer "F.Fab")
			(effects
				(font
					(size 1.27 1.27)
				)
			)
		)
		(duplicate_pad_numbers_are_jumpers no)
		(fp_line
			(start -0.299974 0.150114)
			(end -0.299974 -0.150114)
			(stroke
				(width 0.1)
				(type default)
			)
			(layer "F.Fab")
		)
		(fp_line
			(start 0.299974 0.150114)
			(end -0.299974 0.150114)
			(stroke
				(width 0.1)
				(type default)
			)
			(layer "F.Fab")
		)
		(fp_line
			(start -0.299974 -0.150114)
			(end 0.299974 -0.150114)
			(stroke
				(width 0.1)
				(type default)
			)
			(layer "F.Fab")
		)
		(fp_line
			(start 0.299974 -0.150114)
			(end 0.299974 0.150114)
			(stroke
				(width 0.1)
				(type default)
			)
			(layer "F.Fab")
		)
		(pad "1" smd rect
			(at -0.2667 0 270)
			(size 0.3048 0.381)
			(layers "F.Cu" "F.Mask" "F.Paste")
			(net "P5E_CPU1_P2_TX_BUF_C_DP<9>")
		)
		(pad "2" smd rect
			(at 0.2667 0 270)
			(size 0.3048 0.381)
			(layers "F.Cu" "F.Mask" "F.Paste")
			(net "P5E_CPU1_P2_TX_BUF_DP<9>")
		)
	)
	(footprint ""
		(layer "F.Cu")
		(at 47.18304 -438.753504 -90)
		(property "Reference" "R2912"
			(at 0 0 270)
			(layer "F.SilkS")
			(hide yes)
			(effects
				(font
					(size 1.27 1.27)
				)
			)
		)
		(property "Value" ""
			(at 0 0 270)
			(layer "F.Fab")
			(effects
				(font
					(size 1.27 1.27)
				)
			)
		)
		(duplicate_pad_numbers_are_jumpers no)
		(fp_line
			(start -0.7874 0.4064)
			(end -0.7874 -0.4064)
			(stroke
				(width 0.1524)
				(type default)
			)
			(layer "F.SilkS")
		)
		(fp_line
			(start 0.7874 0.4064)
			(end -0.7874 0.4064)
			(stroke
				(width 0.1524)
				(type default)
			)
			(layer "F.SilkS")
		)
		(fp_line
			(start -0.7874 -0.4064)
			(end 0.7874 -0.4064)
			(stroke
				(width 0.1524)
				(type default)
			)
			(layer "F.SilkS")
		)
		(fp_line
			(start 0.7874 -0.4064)
			(end 0.7874 0.4064)
			(stroke
				(width 0.1524)
				(type default)
			)
			(layer "F.SilkS")
		)
		(fp_line
			(start -0.67945 0.3048)
			(end -0.67945 -0.305054)
			(stroke
				(width 0.1)
				(type default)
			)
			(layer "F.Fab")
		)
		(fp_line
			(start -0.12065 0.3048)
			(end -0.67945 0.3048)
			(stroke
				(width 0.1)
				(type default)
			)
			(layer "F.Fab")
		)
		(fp_line
			(start 0.120396 0.3048)
			(end 0.120396 0.2794)
			(stroke
				(width 0.1)
				(type default)
			)
			(layer "F.Fab")
		)
		(fp_line
			(start 0.67945 0.3048)
			(end 0.120396 0.3048)
			(stroke
				(width 0.1)
				(type default)
			)
			(layer "F.Fab")
		)
		(fp_line
			(start -0.12065 0.2794)
			(end -0.12065 0.3048)
			(stroke
				(width 0.1)
				(type default)
			)
			(layer "F.Fab")
		)
		(fp_line
			(start 0.120396 0.2794)
			(end -0.12065 0.2794)
			(stroke
				(width 0.1)
				(type default)
			)
			(layer "F.Fab")
		)
		(fp_line
			(start -0.12065 -0.2794)
			(end 0.12065 -0.2794)
			(stroke
				(width 0.1)
				(type default)
			)
			(layer "F.Fab")
		)
		(fp_line
			(start 0.12065 -0.2794)
			(end 0.12065 -0.3048)
			(stroke
				(width 0.1)
				(type default)
			)
			(layer "F.Fab")
		)
		(fp_line
			(start 0.12065 -0.3048)
			(end 0.67945 -0.3048)
			(stroke
				(width 0.1)
				(type default)
			)
			(layer "F.Fab")
		)
		(fp_line
			(start 0.67945 -0.3048)
			(end 0.67945 0.3048)
			(stroke
				(width 0.1)
				(type default)
			)
			(layer "F.Fab")
		)
		(fp_line
			(start -0.67945 -0.305054)
			(end -0.12065 -0.305054)
			(stroke
				(width 0.1)
				(type default)
			)
			(layer "F.Fab")
		)
		(fp_line
			(start -0.12065 -0.305054)
			(end -0.12065 -0.2794)
			(stroke
				(width 0.1)
				(type default)
			)
			(layer "F.Fab")
		)
		(pad "1" smd circle
			(at -0.40005 0 270)
			(size 0 0)
			(layers "F.Cu" "F.Mask" "F.Paste")
			(net "P3V3_AUX")
		)
		(pad "2" smd circle
			(at 0.40005 0 270)
			(size 0 0)
			(layers "F.Cu" "F.Mask" "F.Paste")
			(net "FM_GPU_PWR_EN_R1")
		)
	)
	(footprint ""
		(layer "F.Cu")
		(at 211.21116 -16.343122 -90)
		(property "Reference" "R1141"
			(at 0 0 270)
			(layer "F.SilkS")
			(hide yes)
			(effects
				(font
					(size 1.27 1.27)
				)
			)
		)
		(property "Value" ""
			(at 0 0 270)
			(layer "F.Fab")
			(effects
				(font
					(size 1.27 1.27)
				)
			)
		)
		(duplicate_pad_numbers_are_jumpers no)
		(fp_line
			(start -0.7874 0.4064)
			(end -0.7874 -0.4064)
			(stroke
				(width 0.1524)
				(type default)
			)
			(layer "F.SilkS")
		)
		(fp_line
			(start 0.7874 0.4064)
			(end -0.7874 0.4064)
			(stroke
				(width 0.1524)
				(type default)
			)
			(layer "F.SilkS")
		)
		(fp_line
			(start -0.7874 -0.4064)
			(end 0.7874 -0.4064)
			(stroke
				(width 0.1524)
				(type default)
			)
			(layer "F.SilkS")
		)
		(fp_line
			(start 0.7874 -0.4064)
			(end 0.7874 0.4064)
			(stroke
				(width 0.1524)
				(type default)
			)
			(layer "F.SilkS")
		)
		(fp_line
			(start -0.67945 0.3048)
			(end -0.67945 -0.305054)
			(stroke
				(width 0.1)
				(type default)
			)
			(layer "F.Fab")
		)
		(fp_line
			(start -0.12065 0.3048)
			(end -0.67945 0.3048)
			(stroke
				(width 0.1)
				(type default)
			)
			(layer "F.Fab")
		)
		(fp_line
			(start 0.120396 0.3048)
			(end 0.120396 0.2794)
			(stroke
				(width 0.1)
				(type default)
			)
			(layer "F.Fab")
		)
		(fp_line
			(start 0.67945 0.3048)
			(end 0.120396 0.3048)
			(stroke
				(width 0.1)
				(type default)
			)
			(layer "F.Fab")
		)
		(fp_line
			(start -0.12065 0.2794)
			(end -0.12065 0.3048)
			(stroke
				(width 0.1)
				(type default)
			)
			(layer "F.Fab")
		)
		(fp_line
			(start 0.120396 0.2794)
			(end -0.12065 0.2794)
			(stroke
				(width 0.1)
				(type default)
			)
			(layer "F.Fab")
		)
		(fp_line
			(start -0.12065 -0.2794)
			(end 0.12065 -0.2794)
			(stroke
				(width 0.1)
				(type default)
			)
			(layer "F.Fab")
		)
		(fp_line
			(start 0.12065 -0.2794)
			(end 0.12065 -0.3048)
			(stroke
				(width 0.1)
				(type default)
			)
			(layer "F.Fab")
		)
		(fp_line
			(start 0.12065 -0.3048)
			(end 0.67945 -0.3048)
			(stroke
				(width 0.1)
				(type default)
			)
			(layer "F.Fab")
		)
		(fp_line
			(start 0.67945 -0.3048)
			(end 0.67945 0.3048)
			(stroke
				(width 0.1)
				(type default)
			)
			(layer "F.Fab")
		)
		(fp_line
			(start -0.67945 -0.305054)
			(end -0.12065 -0.305054)
			(stroke
				(width 0.1)
				(type default)
			)
			(layer "F.Fab")
		)
		(fp_line
			(start -0.12065 -0.305054)
			(end -0.12065 -0.2794)
			(stroke
				(width 0.1)
				(type default)
			)
			(layer "F.Fab")
		)
		(pad "1" smd circle
			(at -0.40005 0 270)
			(size 0 0)
			(layers "F.Cu" "F.Mask" "F.Paste")
			(net "CLK_50M_NCSI_OCP_1")
		)
		(pad "2" smd circle
			(at 0.40005 0 270)
			(size 0 0)
			(layers "F.Cu" "F.Mask" "F.Paste")
			(net "CLK_50M_NCSI_OCP_SFF")
		)
	)
)
